# T6G (Grand Teton) — schematic netlist excerpt (pin names and nets, part order shuffled) for the footprints in the layout excerpt that follows; sources: Cadence DE-HDL packaged netlist, KiCad conversion of 04192023_DAF0TMB3IC0_F0TG_MB_C_brd_V02_OCP.brd

PU46  ISL99390FRZTR5935  ISL99390FRZ-TR5935 IC  pkg QFN21_6X5XB  page 195
  VOS  = PVDDCR_CPU0_P0_VOS3
  AGND  = GND
  VCC  = PVDDCR_CPU0_P0_VCC3
  PVCC  = PVDDCR_CPU0_P0_PVCC
  PGND1  = GND
  GL1  = NC_PVDDCR_CPU0_P0_GL1_3
  PGND2  = GND
  SW  = SW_PVDDCR_CPU0_P0_SW3
  VIN1  = SW_P12V_AUX_PVDDCR_CPU0_P0_FLT
  VIN2  = SW_P12V_AUX_PVDDCR_CPU0_P0_FLT
  DNC  = NC_PVDDCR_CPU0_P0_DNC3
  PHASE  = SW_PVDDCR_CPU0_P0_PH3
  BOOT  = SW_PVDDCR_CPU0_P0_BOOT3
  PWM  = PVDDCR_CPU0_P0_PWM3
  EN  = PVDDCR_CPU0_P0_VCC3
  TOUT_FLT  = PVDDCR_CPU0_P0_TEMP0
  LSET  = PVDDCR_CPU0_P0_LSET3
  IOUT  = PVDDCR_CPU0_P0_IMON3
  REFIN  = PVDDCR_CPU0_P0_VCCS
  PGND3  = GND
  GL2  = NC_PVDDCR_CPU0_P0_GL2_3

(kicad_pcb
	(version 20260206)
	(generator "pcbnew")
	(generator_version "10.0")
	(general
		(thickness 1.6)
		(legacy_teardrops no)
	)
	(paper "A4")
	(title_block
		(title "04192023_DAF0TMB3IC0_F0TG_MB_C_brd_V02_OCP.brd")
		(comment 1 "Grand Teton / footprints 2578-2578 of 8354")
	)
	(layers
		(0 "F.Cu" signal "TOP")
		(4 "In1.Cu" signal "GND")
		(6 "In2.Cu" signal "IN1")
		(8 "In3.Cu" signal "GND1")
		(10 "In4.Cu" signal "IN2")
		(12 "In5.Cu" signal "GND2")
		(14 "In6.Cu" signal "IN3")
		(16 "In7.Cu" signal "GND3")
		(18 "In8.Cu" signal "VCC")
		(20 "In9.Cu" signal "VCC1")
		(22 "In10.Cu" signal "GND4")
		(24 "In11.Cu" signal "IN4")
		(26 "In12.Cu" signal "GND5")
		(28 "In13.Cu" signal "IN5")
		(30 "In14.Cu" signal "GND6")
		(32 "In15.Cu" signal "IN6")
		(34 "In16.Cu" signal "GND7")
		(2 "B.Cu" signal "BOTTOM")
		(9 "F.Adhes" user "F.Adhesive")
		(11 "B.Adhes" user "B.Adhesive")
		(13 "F.Paste" user "Package Geometry/Pastemask Top")
		(15 "B.Paste" user "Package Geometry/Pastemask Bottom")
		(5 "F.SilkS" user "Ref Des/Silkscreen Top")
		(7 "B.SilkS" user "Ref Des/Silkscreen Bottom")
		(1 "F.Mask" user "Board Geometry/Soldermask Top")
		(3 "B.Mask" user "Board Geometry/Soldermask Bottom")
		(17 "Dwgs.User" user "User.Drawings")
		(19 "Cmts.User" user "User.Comments")
		(21 "Eco1.User" user "User.Eco1")
		(23 "Eco2.User" user "User.Eco2")
		(25 "Edge.Cuts" user "Board Geometry/Outline")
		(27 "Margin" user)
		(31 "F.CrtYd" user "Package Geometry/Place Bound Top")
		(29 "B.CrtYd" user "Package Geometry/Place Bound Bottom")
		(35 "F.Fab" user "Ref Des/Assembly Top")
		(33 "B.Fab" user "Ref Des/Assembly Bottom")
	)
	(footprint ""
		(layer "F.Cu")
		(at 381.077978 -182.786528 180)
		(property "Reference" "PU46"
			(at 1.867916 -7.072122 0)
			(unlocked yes)
			(layer "F.SilkS")
			(effects
				(font
					(size 0.7874 0.5842)
					(thickness 0.1524)
				)
				(justify left)
			)
		)
		(property "Value" ""
			(at 0 0 180)
			(layer "F.Fab")
			(effects
				(font
					(size 1.27 1.27)
				)
			)
		)
		(duplicate_pad_numbers_are_jumpers no)
		(fp_line
			(start 2.500122 2.999994)
			(end 2.2987 2.999994)
			(stroke
				(width 0.1524)
				(type default)
			)
			(layer "F.SilkS")
		)
		(fp_line
			(start 2.500122 2.339594)
			(end 2.500122 2.999994)
			(stroke
				(width 0.1524)
				(type default)
			)
			(layer "F.SilkS")
		)
		(fp_line
			(start 2.500122 -2.999994)
			(end 2.500122 -2.44348)
			(stroke
				(width 0.1524)
				(type default)
			)
			(layer "F.SilkS")
		)
		(fp_line
			(start 2.31394 -2.999994)
			(end 2.500122 -2.999994)
			(stroke
				(width 0.1524)
				(type default)
			)
			(layer "F.SilkS")
		)
		(fp_line
			(start -2.2987 2.999994)
			(end -2.500122 2.999994)
			(stroke
				(width 0.1524)
				(type default)
			)
			(layer "F.SilkS")
		)
		(fp_line
			(start -2.500122 2.999994)
			(end -2.500122 2.339594)
			(stroke
				(width 0.1524)
				(type default)
			)
			(layer "F.SilkS")
		)
		(fp_line
			(start -2.500122 0.6604)
			(end -2.500122 0.229108)
			(stroke
				(width 0.1524)
				(type default)
			)
			(layer "F.SilkS")
		)
		(fp_line
			(start -2.500122 -2.529078)
			(end -2.500122 -2.999994)
			(stroke
				(width 0.1524)
				(type default)
			)
			(layer "F.SilkS")
		)
		(fp_line
			(start -2.500122 -2.999994)
			(end -2.24409 -2.999994)
			(stroke
				(width 0.1524)
				(type default)
			)
			(layer "F.SilkS")
		)
		(fp_poly
			(pts
				(xy -2.788666 -2.483612) (xy -3.45948 -2.707386) (xy -3.01244 -3.154426)
			)
			(stroke
				(width 0)
				(type default)
			)
			(fill yes)
			(layer "F.SilkS")
		)
		(fp_line
			(start 2.500122 2.999994)
			(end -2.500122 2.999994)
			(stroke
				(width 0.1)
				(type default)
			)
			(layer "F.Fab")
		)
		(fp_line
			(start 2.500122 -2.999994)
			(end 2.500122 2.999994)
			(stroke
				(width 0.1)
				(type default)
			)
			(layer "F.Fab")
		)
		(fp_line
			(start -2.500122 2.999994)
			(end -2.500122 -2.999994)
			(stroke
				(width 0.1)
				(type default)
			)
			(layer "F.Fab")
		)
		(fp_line
			(start -2.500122 -2.999994)
			(end 2.500122 -2.999994)
			(stroke
				(width 0.1)
				(type default)
			)
			(layer "F.Fab")
		)
		(fp_poly
			(pts
				(xy -4.218432 -2.783078) (xy -4.218432 -1.767078) (xy -3.202432 -2.275078)
			)
			(stroke
				(width 0)
				(type default)
			)
			(fill yes)
			(layer "F.Fab")
		)
		(pad "1" smd rect
			(at -2.400046 -2.275078 270)
			(size 0.2286 0.6096)
			(layers "F.Cu" "F.Mask" "F.Paste")
			(net "PVDDCR_CPU0_P0_VOS3")
		)
		(pad "2" smd rect
			(at -2.400046 -1.82499 270)
			(size 0.2286 0.6096)
			(layers "F.Cu" "F.Mask" "F.Paste")
			(net "GND")
		)
		(pad "3" smd rect
			(at -2.400046 -1.374902 270)
			(size 0.2286 0.6096)
			(layers "F.Cu" "F.Mask" "F.Paste")
			(net "PVDDCR_CPU0_P0_VCC3")
		)
		(pad "4" smd rect
			(at -2.400046 -0.925068 270)
			(size 0.2286 0.6096)
			(layers "F.Cu" "F.Mask" "F.Paste")
			(net "PVDDCR_CPU0_P0_PVCC")
		)
		(pad "5" smd rect
			(at -2.400046 -0.47498 270)
			(size 0.2286 0.6096)
			(layers "F.Cu" "F.Mask" "F.Paste")
			(net "GND")
		)
		(pad "6" smd rect
			(at -2.400046 -0.024892 270)
			(size 0.2286 0.6096)
			(layers "F.Cu" "F.Mask" "F.Paste")
			(net "NC_PVDDCR_CPU0_P0_GL1_3")
		)
		(pad "7_9-20_24" smd circle
			(at 0 1.150112 270)
			(size 0 0)
			(layers "F.Cu" "F.Mask" "F.Paste")
			(net "GND")
		)
		(pad "10_19" smd rect
			(at 0 2.899918 270)
			(size 0.6096 4.318)
			(layers "F.Cu" "F.Mask" "F.Paste")
			(net "SW_PVDDCR_CPU0_P0_SW3")
		)
		(pad "25_29" smd rect
			(at 1.549908 -1.279906 90)
			(size 2.0574 2.3114)
			(layers "F.Cu" "F.Mask" "F.Paste")
			(net "SW_P12V_AUX_PVDDCR_CPU0_P0_FLT")
		)
		(pad "30" smd rect
			(at 2.05994 -2.899918 180)
			(size 0.2286 0.6096)
			(layers "F.Cu" "F.Mask" "F.Paste")
			(net "SW_P12V_AUX_PVDDCR_CPU0_P0_FLT")
		)
		(pad "31" smd rect
			(at 1.610106 -2.899918 180)
			(size 0.2286 0.6096)
			(layers "F.Cu" "F.Mask" "F.Paste")
			(net "NC_PVDDCR_CPU0_P0_DNC3")
		)
		(pad "32" smd rect
			(at 1.160018 -2.899918 180)
			(size 0.2286 0.6096)
			(layers "F.Cu" "F.Mask" "F.Paste")
			(net "SW_PVDDCR_CPU0_P0_PH3")
		)
		(pad "33" smd rect
			(at 0.70993 -2.899918 180)
			(size 0.2286 0.6096)
			(layers "F.Cu" "F.Mask" "F.Paste")
			(net "SW_PVDDCR_CPU0_P0_BOOT3")
		)
		(pad "34" smd rect
			(at 0.260096 -2.899918 180)
			(size 0.2286 0.6096)
			(layers "F.Cu" "F.Mask" "F.Paste")
			(net "PVDDCR_CPU0_P0_PWM3")
		)
		(pad "35" smd rect
			(at -0.189992 -2.899918 180)
			(size 0.2286 0.6096)
			(layers "F.Cu" "F.Mask" "F.Paste")
			(net "PVDDCR_CPU0_P0_VCC3")
		)
		(pad "36" smd rect
			(at -0.64008 -2.899918 180)
			(size 0.2286 0.6096)
			(layers "F.Cu" "F.Mask" "F.Paste")
			(net "PVDDCR_CPU0_P0_TEMP0")
		)
		(pad "37" smd rect
			(at -1.089914 -2.899918 180)
			(size 0.2286 0.6096)
			(layers "F.Cu" "F.Mask" "F.Paste")
			(net "PVDDCR_CPU0_P0_LSET3")
		)
		(pad "38" smd rect
			(at -1.540002 -2.899918 180)
			(size 0.2286 0.6096)
			(layers "F.Cu" "F.Mask" "F.Paste")
			(net "PVDDCR_CPU0_P0_IMON3")
		)
		(pad "39" smd rect
			(at -1.99009 -2.899918 180)
			(size 0.2286 0.6096)
			(layers "F.Cu" "F.Mask" "F.Paste")
			(net "PVDDCR_CPU0_P0_VCCS")
		)
		(pad "40" smd rect
			(at -0.87503 -1.27508 180)
			(size 1.7526 1.9558)
			(layers "F.Cu" "F.Mask" "F.Paste")
			(net "GND")
		)
		(pad "41" smd rect
			(at -1.525016 0.249936 90)
			(size 0.3048 0.4572)
			(layers "F.Cu" "F.Mask" "F.Paste")
			(net "NC_PVDDCR_CPU0_P0_GL2_3")
		)
		(zone
			(layer "F.Cu")
			(hatch none 0.5)
			(connect_pads
				(clearance 0)
			)
			(min_thickness 0.25)
			(keepout
				(tracks not_allowed)
				(vias allowed)
				(pads allowed)
				(copperpour not_allowed)
				(footprints allowed)
			)
			(placement
				(enabled no)
				(sheetname "")
			)
			(fill
				(thermal_gap 0.5)
				(thermal_bridge_width 0.5)
				(island_removal_mode 0)
			)
			(polygon
				(pts
					(xy 383.5781 -185.334402) (xy 383.5781 -185.037222) (xy 378.577856 -185.037222) (xy 378.577856 -185.33491)
					(xy 378.868178 -185.33491) (xy 378.868178 -185.330846) (xy 383.287778 -185.330846) (xy 383.287778 -185.334402)
				)
			)
		)
		(zone
			(layer "F.Cu")
			(hatch none 0.5)
			(connect_pads
				(clearance 0)
			)
			(min_thickness 0.25)
			(keepout
				(tracks not_allowed)
				(vias allowed)
				(pads allowed)
				(copperpour not_allowed)
				(footprints allowed)
			)
			(placement
				(enabled no)
				(sheetname "")
			)
			(fill
				(thermal_gap 0.5)
				(thermal_bridge_width 0.5)
				(island_removal_mode 0)
			)
			(polygon
				(pts
					(xy 381.025908 -182.53456) (xy 381.025908 -180.482748) (xy 382.880108 -180.482748) (xy 382.880108 -180.723794)
					(xy 383.122424 -180.723794) (xy 383.122424 -180.24221) (xy 379.244098 -180.24221) (xy 379.244098 -180.427122)
					(xy 380.73457 -180.427122) (xy 380.73457 -182.586122) (xy 378.577856 -182.586122) (xy 378.577856 -182.835804)
					(xy 380.724664 -182.835804)
				)
			)
		)
	)
)
